# T6G (Grand Teton) — schematic netlist excerpt (pin names and nets, part order shuffled) for the footprints in the layout excerpt that follows; sources: Cadence DE-HDL packaged netlist, KiCad conversion of 04192023_DAF0TMB3IC0_F0TG_MB_C_brd_V02_OCP.brd

C761  Q_CAP_DIFFBUS  DIFF BUS_0.22UF 6.3V 20% X6S  pkg C0201  page 66 : \1\ = P5E_CPU1_P2_TX_C_DP<6> ; \2\ = P5E_CPU1_P2_TX_DP<6>
C592  Q_CAP  0.1UF 25V 10% X7R  pkg 0402  page 134 : A = P3V3_AUX ; B = GND

(kicad_pcb
	(version 20260206)
	(generator "pcbnew")
	(generator_version "10.0")
	(general
		(thickness 1.6)
		(legacy_teardrops no)
	)
	(paper "A4")
	(title_block
		(title "04192023_DAF0TMB3IC0_F0TG_MB_C_brd_V02_OCP.brd")
		(comment 1 "Grand Teton / footprints 3419-3420 of 8354")
	)
	(layers
		(0 "F.Cu" signal "TOP")
		(4 "In1.Cu" signal "GND")
		(6 "In2.Cu" signal "IN1")
		(8 "In3.Cu" signal "GND1")
		(10 "In4.Cu" signal "IN2")
		(12 "In5.Cu" signal "GND2")
		(14 "In6.Cu" signal "IN3")
		(16 "In7.Cu" signal "GND3")
		(18 "In8.Cu" signal "VCC")
		(20 "In9.Cu" signal "VCC1")
		(22 "In10.Cu" signal "GND4")
		(24 "In11.Cu" signal "IN4")
		(26 "In12.Cu" signal "GND5")
		(28 "In13.Cu" signal "IN5")
		(30 "In14.Cu" signal "GND6")
		(32 "In15.Cu" signal "IN6")
		(34 "In16.Cu" signal "GND7")
		(2 "B.Cu" signal "BOTTOM")
		(9 "F.Adhes" user "F.Adhesive")
		(11 "B.Adhes" user "B.Adhesive")
		(13 "F.Paste" user "Package Geometry/Pastemask Top")
		(15 "B.Paste" user "Package Geometry/Pastemask Bottom")
		(5 "F.SilkS" user "Ref Des/Silkscreen Top")
		(7 "B.SilkS" user "Ref Des/Silkscreen Bottom")
		(1 "F.Mask" user "Board Geometry/Soldermask Top")
		(3 "B.Mask" user "Board Geometry/Soldermask Bottom")
		(17 "Dwgs.User" user "User.Drawings")
		(19 "Cmts.User" user "User.Comments")
		(21 "Eco1.User" user "User.Eco1")
		(23 "Eco2.User" user "User.Eco2")
		(25 "Edge.Cuts" user "Board Geometry/Outline")
		(27 "Margin" user)
		(31 "F.CrtYd" user "Package Geometry/Place Bound Top")
		(29 "B.CrtYd" user "Package Geometry/Place Bound Bottom")
		(35 "F.Fab" user "Ref Des/Assembly Top")
		(33 "B.Fab" user "Ref Des/Assembly Bottom")
	)
	(footprint ""
		(layer "F.Cu")
		(at 151.126444 -370.57203 -90)
		(property "Reference" "C761"
			(at 0 0 270)
			(layer "F.SilkS")
			(hide yes)
			(effects
				(font
					(size 1.27 1.27)
				)
			)
		)
		(property "Value" ""
			(at 0 0 270)
			(layer "F.Fab")
			(effects
				(font
					(size 1.27 1.27)
				)
			)
		)
		(duplicate_pad_numbers_are_jumpers no)
		(fp_line
			(start -0.299974 0.150114)
			(end -0.299974 -0.150114)
			(stroke
				(width 0.1)
				(type default)
			)
			(layer "F.Fab")
		)
		(fp_line
			(start 0.299974 0.150114)
			(end -0.299974 0.150114)
			(stroke
				(width 0.1)
				(type default)
			)
			(layer "F.Fab")
		)
		(fp_line
			(start -0.299974 -0.150114)
			(end 0.299974 -0.150114)
			(stroke
				(width 0.1)
				(type default)
			)
			(layer "F.Fab")
		)
		(fp_line
			(start 0.299974 -0.150114)
			(end 0.299974 0.150114)
			(stroke
				(width 0.1)
				(type default)
			)
			(layer "F.Fab")
		)
		(pad "1" smd rect
			(at -0.2667 0 270)
			(size 0.3048 0.381)
			(layers "F.Cu" "F.Mask" "F.Paste")
			(net "P5E_CPU1_P2_TX_C_DP<6>")
		)
		(pad "2" smd rect
			(at 0.2667 0 270)
			(size 0.3048 0.381)
			(layers "F.Cu" "F.Mask" "F.Paste")
			(net "P5E_CPU1_P2_TX_DP<6>")
		)
	)
	(footprint ""
		(layer "F.Cu")
		(at 461.593946 -107.043728)
		(property "Reference" "C592"
			(at 0 0 0)
			(layer "F.SilkS")
			(hide yes)
			(effects
				(font
					(size 1.27 1.27)
				)
			)
		)
		(property "Value" ""
			(at 0 0 0)
			(layer "F.Fab")
			(effects
				(font
					(size 1.27 1.27)
				)
			)
		)
		(duplicate_pad_numbers_are_jumpers no)
		(fp_line
			(start -0.7874 -0.4064)
			(end 0.7874 -0.4064)
			(stroke
				(width 0.1524)
				(type default)
			)
			(layer "F.SilkS")
		)
		(fp_line
			(start -0.7874 0.4064)
			(end -0.7874 -0.4064)
			(stroke
				(width 0.1524)
				(type default)
			)
			(layer "F.SilkS")
		)
		(fp_line
			(start 0.7874 -0.4064)
			(end 0.7874 0.4064)
			(stroke
				(width 0.1524)
				(type default)
			)
			(layer "F.SilkS")
		)
		(fp_line
			(start 0.7874 0.4064)
			(end -0.7874 0.4064)
			(stroke
				(width 0.1524)
				(type default)
			)
			(layer "F.SilkS")
		)
		(fp_line
			(start -0.67945 -0.305054)
			(end -0.12065 -0.305054)
			(stroke
				(width 0.1)
				(type default)
			)
			(layer "F.Fab")
		)
		(fp_line
			(start -0.67945 0.3048)
			(end -0.67945 -0.305054)
			(stroke
				(width 0.1)
				(type default)
			)
			(layer "F.Fab")
		)
		(fp_line
			(start -0.12065 -0.305054)
			(end -0.12065 -0.2794)
			(stroke
				(width 0.1)
				(type default)
			)
			(layer "F.Fab")
		)
		(fp_line
			(start -0.12065 -0.2794)
			(end 0.12065 -0.2794)
			(stroke
				(width 0.1)
				(type default)
			)
			(layer "F.Fab")
		)
		(fp_line
			(start -0.12065 0.2794)
			(end -0.12065 0.3048)
			(stroke
				(width 0.1)
				(type default)
			)
			(layer "F.Fab")
		)
		(fp_line
			(start -0.12065 0.3048)
			(end -0.67945 0.3048)
			(stroke
				(width 0.1)
				(type default)
			)
			(layer "F.Fab")
		)
		(fp_line
			(start 0.120396 0.2794)
			(end -0.12065 0.2794)
			(stroke
				(width 0.1)
				(type default)
			)
			(layer "F.Fab")
		)
		(fp_line
			(start 0.120396 0.3048)
			(end 0.120396 0.2794)
			(stroke
				(width 0.1)
				(type default)
			)
			(layer "F.Fab")
		)
		(fp_line
			(start 0.12065 -0.3048)
			(end 0.67945 -0.3048)
			(stroke
				(width 0.1)
				(type default)
			)
			(layer "F.Fab")
		)
		(fp_line
			(start 0.12065 -0.2794)
			(end 0.12065 -0.3048)
			(stroke
				(width 0.1)
				(type default)
			)
			(layer "F.Fab")
		)
		(fp_line
			(start 0.67945 -0.3048)
			(end 0.67945 0.3048)
			(stroke
				(width 0.1)
				(type default)
			)
			(layer "F.Fab")
		)
		(fp_line
			(start 0.67945 0.3048)
			(end 0.120396 0.3048)
			(stroke
				(width 0.1)
				(type default)
			)
			(layer "F.Fab")
		)
		(pad "1" smd circle
			(at -0.40005 0)
			(size 0 0)
			(layers "F.Cu" "F.Mask" "F.Paste")
			(net "P3V3_AUX")
		)
		(pad "2" smd circle
			(at 0.40005 0)
			(size 0 0)
			(layers "F.Cu" "F.Mask" "F.Paste")
			(net "GND")
		)
	)
)
